(kicad_pcb
	(version 20260206)
	(generator "pcbnew")
	(generator_version "10.0")
	(general
		(thickness 1.6)
		(legacy_teardrops no)
	)
	(paper "A4")
	(title_block
		(title "01162023_DA0F0TEBIF0_F0T_Expander_BD_F_brd_V02_OCP.brd")
		(comment 1 "Grand Teton / footprints 8949-8956 of 9728")
	)
	(layers
		(0 "F.Cu" signal "TOP")
		(4 "In1.Cu" signal "GND")
		(6 "In2.Cu" signal "VCC")
		(8 "In3.Cu" signal "VCC1")
		(10 "In4.Cu" signal "GND1")
		(12 "In5.Cu" signal "IN1")
		(14 "In6.Cu" signal "GND2")
		(16 "In7.Cu" signal "IN2")
		(18 "In8.Cu" signal "GND3")
		(20 "In9.Cu" signal "IN3")
		(22 "In10.Cu" signal "GND4")
		(24 "In11.Cu" signal "IN4")
		(26 "In12.Cu" signal "GND5")
		(28 "In13.Cu" signal "IN5")
		(30 "In14.Cu" signal "GND6")
		(32 "In15.Cu" signal "IN6")
		(34 "In16.Cu" signal "GND7")
		(2 "B.Cu" signal "BOTTOM")
		(9 "F.Adhes" user "F.Adhesive")
		(11 "B.Adhes" user "B.Adhesive")
		(13 "F.Paste" user "Package Geometry/Pastemask Top")
		(15 "B.Paste" user "Package Geometry/Pastemask Bottom")
		(5 "F.SilkS" user "Ref Des/Silkscreen Top")
		(7 "B.SilkS" user "Ref Des/Silkscreen Bottom")
		(1 "F.Mask" user "Board Geometry/Soldermask Top")
		(3 "B.Mask" user "Board Geometry/Soldermask Bottom")
		(17 "Dwgs.User" user "User.Drawings")
		(19 "Cmts.User" user "User.Comments")
		(21 "Eco1.User" user "User.Eco1")
		(23 "Eco2.User" user "User.Eco2")
		(25 "Edge.Cuts" user "Board Geometry/Outline")
		(27 "Margin" user)
		(31 "F.CrtYd" user "Package Geometry/Place Bound Top")
		(29 "B.CrtYd" user "Package Geometry/Place Bound Bottom")
		(35 "F.Fab" user "Ref Des/Assembly Top")
		(33 "B.Fab" user "Ref Des/Assembly Bottom")
	)
	(footprint ""
		(layer "B.Cu")
		(at 77.541882 -99.037648 180)
		(property "Reference" "R65"
			(at 0 0 0)
			(layer "B.SilkS")
			(hide yes)
			(effects
				(font
					(size 1.27 1.27)
				)
				(justify mirror)
			)
		)
		(property "Value" ""
			(at 0 0 0)
			(layer "B.Fab")
			(effects
				(font
					(size 1.27 1.27)
				)
				(justify mirror)
			)
		)
		(duplicate_pad_numbers_are_jumpers no)
		(fp_line
			(start 0.7874 0.4064)
			(end 0.7874 -0.4064)
			(stroke
				(width 0.1524)
				(type default)
			)
			(layer "B.SilkS")
		)
		(fp_line
			(start 0.7874 -0.4064)
			(end -0.7874 -0.4064)
			(stroke
				(width 0.1524)
				(type default)
			)
			(layer "B.SilkS")
		)
		(fp_line
			(start -0.7874 0.4064)
			(end 0.7874 0.4064)
			(stroke
				(width 0.1524)
				(type default)
			)
			(layer "B.SilkS")
		)
		(fp_line
			(start -0.7874 -0.4064)
			(end -0.7874 0.4064)
			(stroke
				(width 0.1524)
				(type default)
			)
			(layer "B.SilkS")
		)
		(fp_line
			(start 0.67945 0.3048)
			(end 0.67945 -0.305054)
			(stroke
				(width 0.1)
				(type default)
			)
			(layer "B.Fab")
		)
		(fp_line
			(start 0.67945 -0.305054)
			(end 0.12065 -0.305054)
			(stroke
				(width 0.1)
				(type default)
			)
			(layer "B.Fab")
		)
		(fp_line
			(start 0.12065 0.3048)
			(end 0.67945 0.3048)
			(stroke
				(width 0.1)
				(type default)
			)
			(layer "B.Fab")
		)
		(fp_line
			(start 0.12065 0.2794)
			(end 0.12065 0.3048)
			(stroke
				(width 0.1)
				(type default)
			)
			(layer "B.Fab")
		)
		(fp_line
			(start 0.12065 -0.2794)
			(end -0.12065 -0.2794)
			(stroke
				(width 0.1)
				(type default)
			)
			(layer "B.Fab")
		)
		(fp_line
			(start 0.12065 -0.305054)
			(end 0.12065 -0.2794)
			(stroke
				(width 0.1)
				(type default)
			)
			(layer "B.Fab")
		)
		(fp_line
			(start -0.120396 0.3048)
			(end -0.120396 0.2794)
			(stroke
				(width 0.1)
				(type default)
			)
			(layer "B.Fab")
		)
		(fp_line
			(start -0.120396 0.2794)
			(end 0.12065 0.2794)
			(stroke
				(width 0.1)
				(type default)
			)
			(layer "B.Fab")
		)
		(fp_line
			(start -0.12065 -0.2794)
			(end -0.12065 -0.3048)
			(stroke
				(width 0.1)
				(type default)
			)
			(layer "B.Fab")
		)
		(fp_line
			(start -0.12065 -0.3048)
			(end -0.67945 -0.3048)
			(stroke
				(width 0.1)
				(type default)
			)
			(layer "B.Fab")
		)
		(fp_line
			(start -0.67945 0.3048)
			(end -0.120396 0.3048)
			(stroke
				(width 0.1)
				(type default)
			)
			(layer "B.Fab")
		)
		(fp_line
			(start -0.67945 -0.3048)
			(end -0.67945 0.3048)
			(stroke
				(width 0.1)
				(type default)
			)
			(layer "B.Fab")
		)
		(pad "1" smd circle
			(at 0.40005 0)
			(size 0 0)
			(layers "B.Cu" "B.Mask" "B.Paste")
			(net "NIC1_CLK")
		)
		(pad "2" smd circle
			(at -0.40005 0)
			(size 0 0)
			(layers "B.Cu" "B.Mask" "B.Paste")
			(net "GND")
		)
	)
	(footprint ""
		(layer "B.Cu")
		(at 415.549842 -292.099746 90)
		(property "Reference" "C1935"
			(at 0 0 90)
			(layer "B.SilkS")
			(hide yes)
			(effects
				(font
					(size 1.27 1.27)
				)
				(justify mirror)
			)
		)
		(property "Value" ""
			(at 0 0 90)
			(layer "B.Fab")
			(effects
				(font
					(size 1.27 1.27)
				)
				(justify mirror)
			)
		)
		(duplicate_pad_numbers_are_jumpers no)
		(fp_line
			(start 0.299974 -0.150114)
			(end -0.299974 -0.150114)
			(stroke
				(width 0.1)
				(type default)
			)
			(layer "B.Fab")
		)
		(fp_line
			(start -0.299974 -0.150114)
			(end -0.299974 0.150114)
			(stroke
				(width 0.1)
				(type default)
			)
			(layer "B.Fab")
		)
		(fp_line
			(start 0.299974 0.150114)
			(end 0.299974 -0.150114)
			(stroke
				(width 0.1)
				(type default)
			)
			(layer "B.Fab")
		)
		(fp_line
			(start -0.299974 0.150114)
			(end 0.299974 0.150114)
			(stroke
				(width 0.1)
				(type default)
			)
			(layer "B.Fab")
		)
		(pad "1" smd rect
			(at 0.2667 0 270)
			(size 0.3048 0.381)
			(layers "B.Cu" "B.Mask" "B.Paste")
			(net "P0V8_SERDES_VDDA_PEX3")
		)
		(pad "2" smd rect
			(at -0.2667 0 270)
			(size 0.3048 0.381)
			(layers "B.Cu" "B.Mask" "B.Paste")
			(net "GND")
		)
	)
	(footprint ""
		(layer "B.Cu")
		(at 211.393532 -230.644446 90)
		(property "Reference" "R6322"
			(at 0 0 90)
			(layer "B.SilkS")
			(hide yes)
			(effects
				(font
					(size 1.27 1.27)
				)
				(justify mirror)
			)
		)
		(property "Value" ""
			(at 0 0 90)
			(layer "B.Fab")
			(effects
				(font
					(size 1.27 1.27)
				)
				(justify mirror)
			)
		)
		(duplicate_pad_numbers_are_jumpers no)
		(fp_line
			(start 0.7874 -0.4064)
			(end -0.7874 -0.4064)
			(stroke
				(width 0.1524)
				(type default)
			)
			(layer "B.SilkS")
		)
		(fp_line
			(start -0.7874 -0.4064)
			(end -0.7874 0.4064)
			(stroke
				(width 0.1524)
				(type default)
			)
			(layer "B.SilkS")
		)
		(fp_line
			(start 0.7874 0.4064)
			(end 0.7874 -0.4064)
			(stroke
				(width 0.1524)
				(type default)
			)
			(layer "B.SilkS")
		)
		(fp_line
			(start -0.7874 0.4064)
			(end 0.7874 0.4064)
			(stroke
				(width 0.1524)
				(type default)
			)
			(layer "B.SilkS")
		)
		(fp_line
			(start 0.67945 -0.305054)
			(end 0.12065 -0.305054)
			(stroke
				(width 0.1)
				(type default)
			)
			(layer "B.Fab")
		)
		(fp_line
			(start 0.12065 -0.305054)
			(end 0.12065 -0.2794)
			(stroke
				(width 0.1)
				(type default)
			)
			(layer "B.Fab")
		)
		(fp_line
			(start -0.12065 -0.3048)
			(end -0.67945 -0.3048)
			(stroke
				(width 0.1)
				(type default)
			)
			(layer "B.Fab")
		)
		(fp_line
			(start -0.67945 -0.3048)
			(end -0.67945 0.3048)
			(stroke
				(width 0.1)
				(type default)
			)
			(layer "B.Fab")
		)
		(fp_line
			(start 0.12065 -0.2794)
			(end -0.12065 -0.2794)
			(stroke
				(width 0.1)
				(type default)
			)
			(layer "B.Fab")
		)
		(fp_line
			(start -0.12065 -0.2794)
			(end -0.12065 -0.3048)
			(stroke
				(width 0.1)
				(type default)
			)
			(layer "B.Fab")
		)
		(fp_line
			(start 0.12065 0.2794)
			(end 0.12065 0.3048)
			(stroke
				(width 0.1)
				(type default)
			)
			(layer "B.Fab")
		)
		(fp_line
			(start -0.120396 0.2794)
			(end 0.12065 0.2794)
			(stroke
				(width 0.1)
				(type default)
			)
			(layer "B.Fab")
		)
		(fp_line
			(start 0.67945 0.3048)
			(end 0.67945 -0.305054)
			(stroke
				(width 0.1)
				(type default)
			)
			(layer "B.Fab")
		)
		(fp_line
			(start 0.12065 0.3048)
			(end 0.67945 0.3048)
			(stroke
				(width 0.1)
				(type default)
			)
			(layer "B.Fab")
		)
		(fp_line
			(start -0.120396 0.3048)
			(end -0.120396 0.2794)
			(stroke
				(width 0.1)
				(type default)
			)
			(layer "B.Fab")
		)
		(fp_line
			(start -0.67945 0.3048)
			(end -0.120396 0.3048)
			(stroke
				(width 0.1)
				(type default)
			)
			(layer "B.Fab")
		)
		(pad "1" smd circle
			(at 0.40005 0 270)
			(size 0 0)
			(layers "B.Cu" "B.Mask" "B.Paste")
			(net "SMB_PEX0_SCL")
		)
		(pad "2" smd circle
			(at -0.40005 0 270)
			(size 0 0)
			(layers "B.Cu" "B.Mask" "B.Paste")
			(net "SMB_PEX0_MUX_SCL")
		)
	)
	(footprint ""
		(layer "B.Cu")
		(at 353.383088 -321.151758 -90)
		(property "Reference" "R6543"
			(at 0 0 90)
			(layer "B.SilkS")
			(hide yes)
			(effects
				(font
					(size 1.27 1.27)
				)
				(justify mirror)
			)
		)
		(property "Value" ""
			(at 0 0 90)
			(layer "B.Fab")
			(effects
				(font
					(size 1.27 1.27)
				)
				(justify mirror)
			)
		)
		(duplicate_pad_numbers_are_jumpers no)
		(fp_line
			(start -0.7874 0.4064)
			(end 0.7874 0.4064)
			(stroke
				(width 0.1524)
				(type default)
			)
			(layer "B.SilkS")
		)
		(fp_line
			(start 0.7874 0.4064)
			(end 0.7874 -0.4064)
			(stroke
				(width 0.1524)
				(type default)
			)
			(layer "B.SilkS")
		)
		(fp_line
			(start -0.7874 -0.4064)
			(end -0.7874 0.4064)
			(stroke
				(width 0.1524)
				(type default)
			)
			(layer "B.SilkS")
		)
		(fp_line
			(start 0.7874 -0.4064)
			(end -0.7874 -0.4064)
			(stroke
				(width 0.1524)
				(type default)
			)
			(layer "B.SilkS")
		)
		(fp_line
			(start -0.67945 0.3048)
			(end -0.120396 0.3048)
			(stroke
				(width 0.1)
				(type default)
			)
			(layer "B.Fab")
		)
		(fp_line
			(start -0.120396 0.3048)
			(end -0.120396 0.2794)
			(stroke
				(width 0.1)
				(type default)
			)
			(layer "B.Fab")
		)
		(fp_line
			(start 0.12065 0.3048)
			(end 0.67945 0.3048)
			(stroke
				(width 0.1)
				(type default)
			)
			(layer "B.Fab")
		)
		(fp_line
			(start 0.67945 0.3048)
			(end 0.67945 -0.305054)
			(stroke
				(width 0.1)
				(type default)
			)
			(layer "B.Fab")
		)
		(fp_line
			(start -0.120396 0.2794)
			(end 0.12065 0.2794)
			(stroke
				(width 0.1)
				(type default)
			)
			(layer "B.Fab")
		)
		(fp_line
			(start 0.12065 0.2794)
			(end 0.12065 0.3048)
			(stroke
				(width 0.1)
				(type default)
			)
			(layer "B.Fab")
		)
		(fp_line
			(start -0.12065 -0.2794)
			(end -0.12065 -0.3048)
			(stroke
				(width 0.1)
				(type default)
			)
			(layer "B.Fab")
		)
		(fp_line
			(start 0.12065 -0.2794)
			(end -0.12065 -0.2794)
			(stroke
				(width 0.1)
				(type default)
			)
			(layer "B.Fab")
		)
		(fp_line
			(start -0.67945 -0.3048)
			(end -0.67945 0.3048)
			(stroke
				(width 0.1)
				(type default)
			)
			(layer "B.Fab")
		)
		(fp_line
			(start -0.12065 -0.3048)
			(end -0.67945 -0.3048)
			(stroke
				(width 0.1)
				(type default)
			)
			(layer "B.Fab")
		)
		(fp_line
			(start 0.12065 -0.305054)
			(end 0.12065 -0.2794)
			(stroke
				(width 0.1)
				(type default)
			)
			(layer "B.Fab")
		)
		(fp_line
			(start 0.67945 -0.305054)
			(end 0.12065 -0.305054)
			(stroke
				(width 0.1)
				(type default)
			)
			(layer "B.Fab")
		)
		(pad "1" smd circle
			(at 0.40005 0 90)
			(size 0 0)
			(layers "B.Cu" "B.Mask" "B.Paste")
			(net "P0V8_SERDES_VDDA_PEX3")
		)
		(pad "2" smd circle
			(at -0.40005 0 90)
			(size 0 0)
			(layers "B.Cu" "B.Mask" "B.Paste")
			(net "P0V8_SERDES_VDDA_PEX3_C6")
		)
	)
	(footprint ""
		(layer "B.Cu")
		(at 233.467656 -215.104218 180)
		(property "Reference" "C3605"
			(at 0 0 0)
			(layer "B.SilkS")
			(hide yes)
			(effects
				(font
					(size 1.27 1.27)
				)
				(justify mirror)
			)
		)
		(property "Value" ""
			(at 0 0 0)
			(layer "B.Fab")
			(effects
				(font
					(size 1.27 1.27)
				)
				(justify mirror)
			)
		)
		(duplicate_pad_numbers_are_jumpers no)
		(fp_line
			(start 0.69215 0.2921)
			(end 0.69215 -0.2921)
			(stroke
				(width 0.1524)
				(type default)
			)
			(layer "B.SilkS")
		)
		(fp_line
			(start 0.69215 -0.2921)
			(end -0.69215 -0.2921)
			(stroke
				(width 0.1524)
				(type default)
			)
			(layer "B.SilkS")
		)
		(fp_line
			(start -0.69215 0.2921)
			(end 0.69215 0.2921)
			(stroke
				(width 0.1524)
				(type default)
			)
			(layer "B.SilkS")
		)
		(fp_line
			(start -0.69215 -0.2921)
			(end -0.69215 0.2921)
			(stroke
				(width 0.1524)
				(type default)
			)
			(layer "B.SilkS")
		)
		(fp_line
			(start 0.51435 0.2794)
			(end 0.51435 -0.2794)
			(stroke
				(width 0.1)
				(type default)
			)
			(layer "B.Fab")
		)
		(fp_line
			(start 0.51435 -0.2794)
			(end -0.51435 -0.2794)
			(stroke
				(width 0.1)
				(type default)
			)
			(layer "B.Fab")
		)
		(fp_line
			(start -0.51435 0.2794)
			(end 0.51435 0.2794)
			(stroke
				(width 0.1)
				(type default)
			)
			(layer "B.Fab")
		)
		(fp_line
			(start -0.51435 -0.2794)
			(end -0.51435 0.2794)
			(stroke
				(width 0.1)
				(type default)
			)
			(layer "B.Fab")
		)
		(pad "1" smd circle
			(at 0.40005 0)
			(size 0 0)
			(layers "B.Cu" "B.Mask" "B.Paste")
			(net "P1V2_BIC_USB2AV12")
		)
		(pad "2" smd circle
			(at -0.40005 0)
			(size 0 0)
			(layers "B.Cu" "B.Mask" "B.Paste")
			(net "GND")
		)
		(zone
			(layer "B.Cu")
			(hatch none 0.5)
			(connect_pads
				(clearance 0)
			)
			(min_thickness 0.25)
			(keepout
				(tracks not_allowed)
				(vias allowed)
				(pads allowed)
				(copperpour not_allowed)
				(footprints allowed)
			)
			(placement
				(enabled no)
				(sheetname "")
			)
			(fill
				(thermal_gap 0.5)
				(thermal_bridge_width 0.5)
				(island_removal_mode 0)
			)
			(polygon
				(pts
					(xy 233.277156 -215.191848) (xy 233.368596 -215.250014) (xy 233.567986 -215.250014) (xy 233.658156 -215.191848)
					(xy 233.658156 -215.016588) (xy 233.567986 -214.958168) (xy 233.368596 -214.958168) (xy 233.277156 -215.016334)
				)
			)
		)
	)
	(footprint ""
		(layer "B.Cu")
		(at 421.249856 -295.89984 180)
		(property "Reference" "C3508"
			(at 0 0 0)
			(layer "B.SilkS")
			(hide yes)
			(effects
				(font
					(size 1.27 1.27)
				)
				(justify mirror)
			)
		)
		(property "Value" ""
			(at 0 0 0)
			(layer "B.Fab")
			(effects
				(font
					(size 1.27 1.27)
				)
				(justify mirror)
			)
		)
		(duplicate_pad_numbers_are_jumpers no)
		(fp_line
			(start 0.299974 0.150114)
			(end 0.299974 -0.150114)
			(stroke
				(width 0.1)
				(type default)
			)
			(layer "B.Fab")
		)
		(fp_line
			(start 0.299974 -0.150114)
			(end -0.299974 -0.150114)
			(stroke
				(width 0.1)
				(type default)
			)
			(layer "B.Fab")
		)
		(fp_line
			(start -0.299974 0.150114)
			(end 0.299974 0.150114)
			(stroke
				(width 0.1)
				(type default)
			)
			(layer "B.Fab")
		)
		(fp_line
			(start -0.299974 -0.150114)
			(end -0.299974 0.150114)
			(stroke
				(width 0.1)
				(type default)
			)
			(layer "B.Fab")
		)
		(pad "1" smd rect
			(at 0.2667 0)
			(size 0.3048 0.381)
			(layers "B.Cu" "B.Mask" "B.Paste")
			(net "P1V25_SERDES_VDDPLL_PEX3")
		)
		(pad "2" smd rect
			(at -0.2667 0)
			(size 0.3048 0.381)
			(layers "B.Cu" "B.Mask" "B.Paste")
			(net "GND")
		)
	)
	(footprint ""
		(layer "B.Cu")
		(at 380.746 -241.681 90)
		(property "Reference" "C2573"
			(at 0 0 90)
			(layer "B.SilkS")
			(hide yes)
			(effects
				(font
					(size 1.27 1.27)
				)
				(justify mirror)
			)
		)
		(property "Value" ""
			(at 0 0 90)
			(layer "B.Fab")
			(effects
				(font
					(size 1.27 1.27)
				)
				(justify mirror)
			)
		)
		(duplicate_pad_numbers_are_jumpers no)
		(fp_line
			(start 0.7874 -0.4064)
			(end -0.7874 -0.4064)
			(stroke
				(width 0.1524)
				(type default)
			)
			(layer "B.SilkS")
		)
		(fp_line
			(start -0.7874 -0.4064)
			(end -0.7874 0.4064)
			(stroke
				(width 0.1524)
				(type default)
			)
			(layer "B.SilkS")
		)
		(fp_line
			(start 0.7874 0.4064)
			(end 0.7874 -0.4064)
			(stroke
				(width 0.1524)
				(type default)
			)
			(layer "B.SilkS")
		)
		(fp_line
			(start -0.7874 0.4064)
			(end 0.7874 0.4064)
			(stroke
				(width 0.1524)
				(type default)
			)
			(layer "B.SilkS")
		)
		(fp_line
			(start 0.67945 -0.305054)
			(end 0.12065 -0.305054)
			(stroke
				(width 0.1)
				(type default)
			)
			(layer "B.Fab")
		)
		(fp_line
			(start 0.12065 -0.305054)
			(end 0.12065 -0.2794)
			(stroke
				(width 0.1)
				(type default)
			)
			(layer "B.Fab")
		)
		(fp_line
			(start -0.12065 -0.3048)
			(end -0.67945 -0.3048)
			(stroke
				(width 0.1)
				(type default)
			)
			(layer "B.Fab")
		)
		(fp_line
			(start -0.67945 -0.3048)
			(end -0.67945 0.3048)
			(stroke
				(width 0.1)
				(type default)
			)
			(layer "B.Fab")
		)
		(fp_line
			(start 0.12065 -0.2794)
			(end -0.12065 -0.2794)
			(stroke
				(width 0.1)
				(type default)
			)
			(layer "B.Fab")
		)
		(fp_line
			(start -0.12065 -0.2794)
			(end -0.12065 -0.3048)
			(stroke
				(width 0.1)
				(type default)
			)
			(layer "B.Fab")
		)
		(fp_line
			(start 0.12065 0.2794)
			(end 0.12065 0.3048)
			(stroke
				(width 0.1)
				(type default)
			)
			(layer "B.Fab")
		)
		(fp_line
			(start -0.120396 0.2794)
			(end 0.12065 0.2794)
			(stroke
				(width 0.1)
				(type default)
			)
			(layer "B.Fab")
		)
		(fp_line
			(start 0.67945 0.3048)
			(end 0.67945 -0.305054)
			(stroke
				(width 0.1)
				(type default)
			)
			(layer "B.Fab")
		)
		(fp_line
			(start 0.12065 0.3048)
			(end 0.67945 0.3048)
			(stroke
				(width 0.1)
				(type default)
			)
			(layer "B.Fab")
		)
		(fp_line
			(start -0.120396 0.3048)
			(end -0.120396 0.2794)
			(stroke
				(width 0.1)
				(type default)
			)
			(layer "B.Fab")
		)
		(fp_line
			(start -0.67945 0.3048)
			(end -0.120396 0.3048)
			(stroke
				(width 0.1)
				(type default)
			)
			(layer "B.Fab")
		)
		(pad "1" smd circle
			(at 0.40005 0 270)
			(size 0 0)
			(layers "B.Cu" "B.Mask" "B.Paste")
			(net "P1V8_SDB_VCORE")
		)
		(pad "2" smd circle
			(at -0.40005 0 270)
			(size 0 0)
			(layers "B.Cu" "B.Mask" "B.Paste")
			(net "GND")
		)
	)
	(footprint ""
		(layer "B.Cu")
		(at 285.674816 -293.99992 -90)
		(property "Reference" "C1665"
			(at 0 0 90)
			(layer "B.SilkS")
			(hide yes)
			(effects
				(font
					(size 1.27 1.27)
				)
				(justify mirror)
			)
		)
		(property "Value" ""
			(at 0 0 90)
			(layer "B.Fab")
			(effects
				(font
					(size 1.27 1.27)
				)
				(justify mirror)
			)
		)
		(duplicate_pad_numbers_are_jumpers no)
		(fp_line
			(start -0.299974 0.150114)
			(end 0.299974 0.150114)
			(stroke
				(width 0.1)
				(type default)
			)
			(layer "B.Fab")
		)
		(fp_line
			(start 0.299974 0.150114)
			(end 0.299974 -0.150114)
			(stroke
				(width 0.1)
				(type default)
			)
			(layer "B.Fab")
		)
		(fp_line
			(start -0.299974 -0.150114)
			(end -0.299974 0.150114)
			(stroke
				(width 0.1)
				(type default)
			)
			(layer "B.Fab")
		)
		(fp_line
			(start 0.299974 -0.150114)
			(end -0.299974 -0.150114)
			(stroke
				(width 0.1)
				(type default)
			)
			(layer "B.Fab")
		)
		(pad "1" smd rect
			(at 0.2667 0 90)
			(size 0.3048 0.381)
			(layers "B.Cu" "B.Mask" "B.Paste")
			(net "P0V8_PEX2")
		)
		(pad "2" smd rect
			(at -0.2667 0 90)
			(size 0.3048 0.381)
			(layers "B.Cu" "B.Mask" "B.Paste")
			(net "GND")
		)
	)
)
